(kicad_pcb
	(version 20260206)
	(generator "pcbnew")
	(generator_version "10.0")
	(general
		(thickness 1.6)
		(legacy_teardrops no)
	)
	(paper "A4")
	(title_block
		(title "04192023_DAF0TMB3IC0_F0TG_MB_C_brd_V02_OCP.brd")
		(comment 1 "Grand Teton / footprints 4486-4491 of 8354")
	)
	(layers
		(0 "F.Cu" signal "TOP")
		(4 "In1.Cu" signal "GND")
		(6 "In2.Cu" signal "IN1")
		(8 "In3.Cu" signal "GND1")
		(10 "In4.Cu" signal "IN2")
		(12 "In5.Cu" signal "GND2")
		(14 "In6.Cu" signal "IN3")
		(16 "In7.Cu" signal "GND3")
		(18 "In8.Cu" signal "VCC")
		(20 "In9.Cu" signal "VCC1")
		(22 "In10.Cu" signal "GND4")
		(24 "In11.Cu" signal "IN4")
		(26 "In12.Cu" signal "GND5")
		(28 "In13.Cu" signal "IN5")
		(30 "In14.Cu" signal "GND6")
		(32 "In15.Cu" signal "IN6")
		(34 "In16.Cu" signal "GND7")
		(2 "B.Cu" signal "BOTTOM")
		(9 "F.Adhes" user "F.Adhesive")
		(11 "B.Adhes" user "B.Adhesive")
		(13 "F.Paste" user "Package Geometry/Pastemask Top")
		(15 "B.Paste" user "Package Geometry/Pastemask Bottom")
		(5 "F.SilkS" user "Ref Des/Silkscreen Top")
		(7 "B.SilkS" user "Ref Des/Silkscreen Bottom")
		(1 "F.Mask" user "Board Geometry/Soldermask Top")
		(3 "B.Mask" user "Board Geometry/Soldermask Bottom")
		(17 "Dwgs.User" user "User.Drawings")
		(19 "Cmts.User" user "User.Comments")
		(21 "Eco1.User" user "User.Eco1")
		(23 "Eco2.User" user "User.Eco2")
		(25 "Edge.Cuts" user "Board Geometry/Outline")
		(27 "Margin" user)
		(31 "F.CrtYd" user "Package Geometry/Place Bound Top")
		(29 "B.CrtYd" user "Package Geometry/Place Bound Bottom")
		(35 "F.Fab" user "Ref Des/Assembly Top")
		(33 "B.Fab" user "Ref Des/Assembly Bottom")
	)
	(footprint ""
		(layer "F.Cu")
		(at 215.4301 -406.052782)
		(property "Reference" "PR3922"
			(at 0 0 0)
			(layer "F.SilkS")
			(hide yes)
			(effects
				(font
					(size 1.27 1.27)
				)
			)
		)
		(property "Value" ""
			(at 0 0 0)
			(layer "F.Fab")
			(effects
				(font
					(size 1.27 1.27)
				)
			)
		)
		(duplicate_pad_numbers_are_jumpers no)
		(fp_line
			(start -0.7874 -0.4064)
			(end 0.7874 -0.4064)
			(stroke
				(width 0.1524)
				(type default)
			)
			(layer "F.SilkS")
		)
		(fp_line
			(start -0.7874 0.4064)
			(end -0.7874 -0.4064)
			(stroke
				(width 0.1524)
				(type default)
			)
			(layer "F.SilkS")
		)
		(fp_line
			(start 0.7874 -0.4064)
			(end 0.7874 0.4064)
			(stroke
				(width 0.1524)
				(type default)
			)
			(layer "F.SilkS")
		)
		(fp_line
			(start 0.7874 0.4064)
			(end -0.7874 0.4064)
			(stroke
				(width 0.1524)
				(type default)
			)
			(layer "F.SilkS")
		)
		(fp_line
			(start -0.67945 -0.305054)
			(end -0.12065 -0.305054)
			(stroke
				(width 0.1)
				(type default)
			)
			(layer "F.Fab")
		)
		(fp_line
			(start -0.67945 0.3048)
			(end -0.67945 -0.305054)
			(stroke
				(width 0.1)
				(type default)
			)
			(layer "F.Fab")
		)
		(fp_line
			(start -0.12065 -0.305054)
			(end -0.12065 -0.2794)
			(stroke
				(width 0.1)
				(type default)
			)
			(layer "F.Fab")
		)
		(fp_line
			(start -0.12065 -0.2794)
			(end 0.12065 -0.2794)
			(stroke
				(width 0.1)
				(type default)
			)
			(layer "F.Fab")
		)
		(fp_line
			(start -0.12065 0.2794)
			(end -0.12065 0.3048)
			(stroke
				(width 0.1)
				(type default)
			)
			(layer "F.Fab")
		)
		(fp_line
			(start -0.12065 0.3048)
			(end -0.67945 0.3048)
			(stroke
				(width 0.1)
				(type default)
			)
			(layer "F.Fab")
		)
		(fp_line
			(start 0.120396 0.2794)
			(end -0.12065 0.2794)
			(stroke
				(width 0.1)
				(type default)
			)
			(layer "F.Fab")
		)
		(fp_line
			(start 0.120396 0.3048)
			(end 0.120396 0.2794)
			(stroke
				(width 0.1)
				(type default)
			)
			(layer "F.Fab")
		)
		(fp_line
			(start 0.12065 -0.3048)
			(end 0.67945 -0.3048)
			(stroke
				(width 0.1)
				(type default)
			)
			(layer "F.Fab")
		)
		(fp_line
			(start 0.12065 -0.2794)
			(end 0.12065 -0.3048)
			(stroke
				(width 0.1)
				(type default)
			)
			(layer "F.Fab")
		)
		(fp_line
			(start 0.67945 -0.3048)
			(end 0.67945 0.3048)
			(stroke
				(width 0.1)
				(type default)
			)
			(layer "F.Fab")
		)
		(fp_line
			(start 0.67945 0.3048)
			(end 0.120396 0.3048)
			(stroke
				(width 0.1)
				(type default)
			)
			(layer "F.Fab")
		)
		(pad "1" smd circle
			(at -0.40005 0)
			(size 0 0)
			(layers "F.Cu" "F.Mask" "F.Paste")
			(net "HSC_FLT_TYPE_2")
		)
		(pad "2" smd circle
			(at 0.40005 0)
			(size 0 0)
			(layers "F.Cu" "F.Mask" "F.Paste")
			(net "HSC_FLT_TYPE")
		)
	)
	(footprint ""
		(layer "F.Cu")
		(at 147.877022 -23.284942 90)
		(property "Reference" "C6000"
			(at 0 0 90)
			(layer "F.SilkS")
			(hide yes)
			(effects
				(font
					(size 1.27 1.27)
				)
			)
		)
		(property "Value" ""
			(at 0 0 90)
			(layer "F.Fab")
			(effects
				(font
					(size 1.27 1.27)
				)
			)
		)
		(duplicate_pad_numbers_are_jumpers no)
		(fp_line
			(start 0.7874 -0.4064)
			(end 0.7874 0.4064)
			(stroke
				(width 0.1524)
				(type default)
			)
			(layer "F.SilkS")
		)
		(fp_line
			(start -0.7874 -0.4064)
			(end 0.7874 -0.4064)
			(stroke
				(width 0.1524)
				(type default)
			)
			(layer "F.SilkS")
		)
		(fp_line
			(start 0.7874 0.4064)
			(end -0.7874 0.4064)
			(stroke
				(width 0.1524)
				(type default)
			)
			(layer "F.SilkS")
		)
		(fp_line
			(start -0.7874 0.4064)
			(end -0.7874 -0.4064)
			(stroke
				(width 0.1524)
				(type default)
			)
			(layer "F.SilkS")
		)
		(fp_line
			(start -0.12065 -0.305054)
			(end -0.12065 -0.2794)
			(stroke
				(width 0.1)
				(type default)
			)
			(layer "F.Fab")
		)
		(fp_line
			(start -0.67945 -0.305054)
			(end -0.12065 -0.305054)
			(stroke
				(width 0.1)
				(type default)
			)
			(layer "F.Fab")
		)
		(fp_line
			(start 0.67945 -0.3048)
			(end 0.67945 0.3048)
			(stroke
				(width 0.1)
				(type default)
			)
			(layer "F.Fab")
		)
		(fp_line
			(start 0.12065 -0.3048)
			(end 0.67945 -0.3048)
			(stroke
				(width 0.1)
				(type default)
			)
			(layer "F.Fab")
		)
		(fp_line
			(start 0.12065 -0.2794)
			(end 0.12065 -0.3048)
			(stroke
				(width 0.1)
				(type default)
			)
			(layer "F.Fab")
		)
		(fp_line
			(start -0.12065 -0.2794)
			(end 0.12065 -0.2794)
			(stroke
				(width 0.1)
				(type default)
			)
			(layer "F.Fab")
		)
		(fp_line
			(start 0.120396 0.2794)
			(end -0.12065 0.2794)
			(stroke
				(width 0.1)
				(type default)
			)
			(layer "F.Fab")
		)
		(fp_line
			(start -0.12065 0.2794)
			(end -0.12065 0.3048)
			(stroke
				(width 0.1)
				(type default)
			)
			(layer "F.Fab")
		)
		(fp_line
			(start 0.67945 0.3048)
			(end 0.120396 0.3048)
			(stroke
				(width 0.1)
				(type default)
			)
			(layer "F.Fab")
		)
		(fp_line
			(start 0.120396 0.3048)
			(end 0.120396 0.2794)
			(stroke
				(width 0.1)
				(type default)
			)
			(layer "F.Fab")
		)
		(fp_line
			(start -0.12065 0.3048)
			(end -0.67945 0.3048)
			(stroke
				(width 0.1)
				(type default)
			)
			(layer "F.Fab")
		)
		(fp_line
			(start -0.67945 0.3048)
			(end -0.67945 -0.305054)
			(stroke
				(width 0.1)
				(type default)
			)
			(layer "F.Fab")
		)
		(pad "1" smd circle
			(at -0.40005 0 90)
			(size 0 0)
			(layers "F.Cu" "F.Mask" "F.Paste")
			(net "SCM_VDD_RTC")
		)
		(pad "2" smd circle
			(at 0.40005 0 90)
			(size 0 0)
			(layers "F.Cu" "F.Mask" "F.Paste")
			(net "GND")
		)
	)
	(footprint ""
		(layer "F.Cu")
		(at 115.70589 -257.74523)
		(property "Reference" "C2423"
			(at 0 0 0)
			(layer "F.SilkS")
			(hide yes)
			(effects
				(font
					(size 1.27 1.27)
				)
			)
		)
		(property "Value" ""
			(at 0 0 0)
			(layer "F.Fab")
			(effects
				(font
					(size 1.27 1.27)
				)
			)
		)
		(duplicate_pad_numbers_are_jumpers no)
		(fp_line
			(start -0.7874 -0.4064)
			(end 0.7874 -0.4064)
			(stroke
				(width 0.1524)
				(type default)
			)
			(layer "F.SilkS")
		)
		(fp_line
			(start -0.7874 0.4064)
			(end -0.7874 -0.4064)
			(stroke
				(width 0.1524)
				(type default)
			)
			(layer "F.SilkS")
		)
		(fp_line
			(start 0.7874 -0.4064)
			(end 0.7874 0.4064)
			(stroke
				(width 0.1524)
				(type default)
			)
			(layer "F.SilkS")
		)
		(fp_line
			(start 0.7874 0.4064)
			(end -0.7874 0.4064)
			(stroke
				(width 0.1524)
				(type default)
			)
			(layer "F.SilkS")
		)
		(fp_line
			(start -0.67945 -0.305054)
			(end -0.12065 -0.305054)
			(stroke
				(width 0.1)
				(type default)
			)
			(layer "F.Fab")
		)
		(fp_line
			(start -0.67945 0.3048)
			(end -0.67945 -0.305054)
			(stroke
				(width 0.1)
				(type default)
			)
			(layer "F.Fab")
		)
		(fp_line
			(start -0.12065 -0.305054)
			(end -0.12065 -0.2794)
			(stroke
				(width 0.1)
				(type default)
			)
			(layer "F.Fab")
		)
		(fp_line
			(start -0.12065 -0.2794)
			(end 0.12065 -0.2794)
			(stroke
				(width 0.1)
				(type default)
			)
			(layer "F.Fab")
		)
		(fp_line
			(start -0.12065 0.2794)
			(end -0.12065 0.3048)
			(stroke
				(width 0.1)
				(type default)
			)
			(layer "F.Fab")
		)
		(fp_line
			(start -0.12065 0.3048)
			(end -0.67945 0.3048)
			(stroke
				(width 0.1)
				(type default)
			)
			(layer "F.Fab")
		)
		(fp_line
			(start 0.120396 0.2794)
			(end -0.12065 0.2794)
			(stroke
				(width 0.1)
				(type default)
			)
			(layer "F.Fab")
		)
		(fp_line
			(start 0.120396 0.3048)
			(end 0.120396 0.2794)
			(stroke
				(width 0.1)
				(type default)
			)
			(layer "F.Fab")
		)
		(fp_line
			(start 0.12065 -0.3048)
			(end 0.67945 -0.3048)
			(stroke
				(width 0.1)
				(type default)
			)
			(layer "F.Fab")
		)
		(fp_line
			(start 0.12065 -0.2794)
			(end 0.12065 -0.3048)
			(stroke
				(width 0.1)
				(type default)
			)
			(layer "F.Fab")
		)
		(fp_line
			(start 0.67945 -0.3048)
			(end 0.67945 0.3048)
			(stroke
				(width 0.1)
				(type default)
			)
			(layer "F.Fab")
		)
		(fp_line
			(start 0.67945 0.3048)
			(end 0.120396 0.3048)
			(stroke
				(width 0.1)
				(type default)
			)
			(layer "F.Fab")
		)
		(pad "1" smd circle
			(at -0.40005 0)
			(size 0 0)
			(layers "F.Cu" "F.Mask" "F.Paste")
			(net "PVDDCR_SOC_P1")
		)
		(pad "2" smd circle
			(at 0.40005 0)
			(size 0 0)
			(layers "F.Cu" "F.Mask" "F.Paste")
			(net "GND")
		)
	)
	(footprint ""
		(layer "F.Cu")
		(at 353.900232 -255.554988)
		(property "Reference" "C2164"
			(at 0 0 0)
			(layer "F.SilkS")
			(hide yes)
			(effects
				(font
					(size 1.27 1.27)
				)
			)
		)
		(property "Value" ""
			(at 0 0 0)
			(layer "F.Fab")
			(effects
				(font
					(size 1.27 1.27)
				)
			)
		)
		(duplicate_pad_numbers_are_jumpers no)
		(fp_line
			(start -0.7874 -0.4064)
			(end 0.7874 -0.4064)
			(stroke
				(width 0.1524)
				(type default)
			)
			(layer "F.SilkS")
		)
		(fp_line
			(start -0.7874 0.4064)
			(end -0.7874 -0.4064)
			(stroke
				(width 0.1524)
				(type default)
			)
			(layer "F.SilkS")
		)
		(fp_line
			(start 0.7874 -0.4064)
			(end 0.7874 0.4064)
			(stroke
				(width 0.1524)
				(type default)
			)
			(layer "F.SilkS")
		)
		(fp_line
			(start 0.7874 0.4064)
			(end -0.7874 0.4064)
			(stroke
				(width 0.1524)
				(type default)
			)
			(layer "F.SilkS")
		)
		(fp_line
			(start -0.67945 -0.305054)
			(end -0.12065 -0.305054)
			(stroke
				(width 0.1)
				(type default)
			)
			(layer "F.Fab")
		)
		(fp_line
			(start -0.67945 0.3048)
			(end -0.67945 -0.305054)
			(stroke
				(width 0.1)
				(type default)
			)
			(layer "F.Fab")
		)
		(fp_line
			(start -0.12065 -0.305054)
			(end -0.12065 -0.2794)
			(stroke
				(width 0.1)
				(type default)
			)
			(layer "F.Fab")
		)
		(fp_line
			(start -0.12065 -0.2794)
			(end 0.12065 -0.2794)
			(stroke
				(width 0.1)
				(type default)
			)
			(layer "F.Fab")
		)
		(fp_line
			(start -0.12065 0.2794)
			(end -0.12065 0.3048)
			(stroke
				(width 0.1)
				(type default)
			)
			(layer "F.Fab")
		)
		(fp_line
			(start -0.12065 0.3048)
			(end -0.67945 0.3048)
			(stroke
				(width 0.1)
				(type default)
			)
			(layer "F.Fab")
		)
		(fp_line
			(start 0.120396 0.2794)
			(end -0.12065 0.2794)
			(stroke
				(width 0.1)
				(type default)
			)
			(layer "F.Fab")
		)
		(fp_line
			(start 0.120396 0.3048)
			(end 0.120396 0.2794)
			(stroke
				(width 0.1)
				(type default)
			)
			(layer "F.Fab")
		)
		(fp_line
			(start 0.12065 -0.3048)
			(end 0.67945 -0.3048)
			(stroke
				(width 0.1)
				(type default)
			)
			(layer "F.Fab")
		)
		(fp_line
			(start 0.12065 -0.2794)
			(end 0.12065 -0.3048)
			(stroke
				(width 0.1)
				(type default)
			)
			(layer "F.Fab")
		)
		(fp_line
			(start 0.67945 -0.3048)
			(end 0.67945 0.3048)
			(stroke
				(width 0.1)
				(type default)
			)
			(layer "F.Fab")
		)
		(fp_line
			(start 0.67945 0.3048)
			(end 0.120396 0.3048)
			(stroke
				(width 0.1)
				(type default)
			)
			(layer "F.Fab")
		)
		(pad "1" smd circle
			(at -0.40005 0)
			(size 0 0)
			(layers "F.Cu" "F.Mask" "F.Paste")
			(net "PVDD18_S5_P0")
		)
		(pad "2" smd circle
			(at 0.40005 0)
			(size 0 0)
			(layers "F.Cu" "F.Mask" "F.Paste")
			(net "GND")
		)
	)
	(footprint ""
		(layer "F.Cu")
		(at 429.136302 -434.386736 -90)
		(property "Reference" "C1754"
			(at 0 0 270)
			(layer "F.SilkS")
			(hide yes)
			(effects
				(font
					(size 1.27 1.27)
				)
			)
		)
		(property "Value" ""
			(at 0 0 270)
			(layer "F.Fab")
			(effects
				(font
					(size 1.27 1.27)
				)
			)
		)
		(duplicate_pad_numbers_are_jumpers no)
		(fp_line
			(start -0.7874 0.4064)
			(end -0.7874 -0.4064)
			(stroke
				(width 0.1524)
				(type default)
			)
			(layer "F.SilkS")
		)
		(fp_line
			(start 0.7874 0.4064)
			(end -0.7874 0.4064)
			(stroke
				(width 0.1524)
				(type default)
			)
			(layer "F.SilkS")
		)
		(fp_line
			(start -0.7874 -0.4064)
			(end 0.7874 -0.4064)
			(stroke
				(width 0.1524)
				(type default)
			)
			(layer "F.SilkS")
		)
		(fp_line
			(start 0.7874 -0.4064)
			(end 0.7874 0.4064)
			(stroke
				(width 0.1524)
				(type default)
			)
			(layer "F.SilkS")
		)
		(fp_line
			(start -0.67945 0.3048)
			(end -0.67945 -0.305054)
			(stroke
				(width 0.1)
				(type default)
			)
			(layer "F.Fab")
		)
		(fp_line
			(start -0.12065 0.3048)
			(end -0.67945 0.3048)
			(stroke
				(width 0.1)
				(type default)
			)
			(layer "F.Fab")
		)
		(fp_line
			(start 0.120396 0.3048)
			(end 0.120396 0.2794)
			(stroke
				(width 0.1)
				(type default)
			)
			(layer "F.Fab")
		)
		(fp_line
			(start 0.67945 0.3048)
			(end 0.120396 0.3048)
			(stroke
				(width 0.1)
				(type default)
			)
			(layer "F.Fab")
		)
		(fp_line
			(start -0.12065 0.2794)
			(end -0.12065 0.3048)
			(stroke
				(width 0.1)
				(type default)
			)
			(layer "F.Fab")
		)
		(fp_line
			(start 0.120396 0.2794)
			(end -0.12065 0.2794)
			(stroke
				(width 0.1)
				(type default)
			)
			(layer "F.Fab")
		)
		(fp_line
			(start -0.12065 -0.2794)
			(end 0.12065 -0.2794)
			(stroke
				(width 0.1)
				(type default)
			)
			(layer "F.Fab")
		)
		(fp_line
			(start 0.12065 -0.2794)
			(end 0.12065 -0.3048)
			(stroke
				(width 0.1)
				(type default)
			)
			(layer "F.Fab")
		)
		(fp_line
			(start 0.12065 -0.3048)
			(end 0.67945 -0.3048)
			(stroke
				(width 0.1)
				(type default)
			)
			(layer "F.Fab")
		)
		(fp_line
			(start 0.67945 -0.3048)
			(end 0.67945 0.3048)
			(stroke
				(width 0.1)
				(type default)
			)
			(layer "F.Fab")
		)
		(fp_line
			(start -0.67945 -0.305054)
			(end -0.12065 -0.305054)
			(stroke
				(width 0.1)
				(type default)
			)
			(layer "F.Fab")
		)
		(fp_line
			(start -0.12065 -0.305054)
			(end -0.12065 -0.2794)
			(stroke
				(width 0.1)
				(type default)
			)
			(layer "F.Fab")
		)
		(pad "1" smd circle
			(at -0.40005 0 270)
			(size 0 0)
			(layers "F.Cu" "F.Mask" "F.Paste")
			(net "FM_SWB_BIC_READY_ISO_N")
		)
		(pad "2" smd circle
			(at 0.40005 0 270)
			(size 0 0)
			(layers "F.Cu" "F.Mask" "F.Paste")
			(net "GND")
		)
	)
	(footprint ""
		(layer "F.Cu")
		(at 294.421052 -122.349514)
		(property "Reference" "R317"
			(at 0 0 0)
			(layer "F.SilkS")
			(hide yes)
			(effects
				(font
					(size 1.27 1.27)
				)
			)
		)
		(property "Value" ""
			(at 0 0 0)
			(layer "F.Fab")
			(effects
				(font
					(size 1.27 1.27)
				)
			)
		)
		(duplicate_pad_numbers_are_jumpers no)
		(fp_line
			(start -0.7874 -0.4064)
			(end 0.7874 -0.4064)
			(stroke
				(width 0.1524)
				(type default)
			)
			(layer "F.SilkS")
		)
		(fp_line
			(start -0.7874 0.4064)
			(end -0.7874 -0.4064)
			(stroke
				(width 0.1524)
				(type default)
			)
			(layer "F.SilkS")
		)
		(fp_line
			(start 0.7874 -0.4064)
			(end 0.7874 0.4064)
			(stroke
				(width 0.1524)
				(type default)
			)
			(layer "F.SilkS")
		)
		(fp_line
			(start 0.7874 0.4064)
			(end -0.7874 0.4064)
			(stroke
				(width 0.1524)
				(type default)
			)
			(layer "F.SilkS")
		)
		(fp_line
			(start -0.67945 -0.305054)
			(end -0.12065 -0.305054)
			(stroke
				(width 0.1)
				(type default)
			)
			(layer "F.Fab")
		)
		(fp_line
			(start -0.67945 0.3048)
			(end -0.67945 -0.305054)
			(stroke
				(width 0.1)
				(type default)
			)
			(layer "F.Fab")
		)
		(fp_line
			(start -0.12065 -0.305054)
			(end -0.12065 -0.2794)
			(stroke
				(width 0.1)
				(type default)
			)
			(layer "F.Fab")
		)
		(fp_line
			(start -0.12065 -0.2794)
			(end 0.12065 -0.2794)
			(stroke
				(width 0.1)
				(type default)
			)
			(layer "F.Fab")
		)
		(fp_line
			(start -0.12065 0.2794)
			(end -0.12065 0.3048)
			(stroke
				(width 0.1)
				(type default)
			)
			(layer "F.Fab")
		)
		(fp_line
			(start -0.12065 0.3048)
			(end -0.67945 0.3048)
			(stroke
				(width 0.1)
				(type default)
			)
			(layer "F.Fab")
		)
		(fp_line
			(start 0.120396 0.2794)
			(end -0.12065 0.2794)
			(stroke
				(width 0.1)
				(type default)
			)
			(layer "F.Fab")
		)
		(fp_line
			(start 0.120396 0.3048)
			(end 0.120396 0.2794)
			(stroke
				(width 0.1)
				(type default)
			)
			(layer "F.Fab")
		)
		(fp_line
			(start 0.12065 -0.3048)
			(end 0.67945 -0.3048)
			(stroke
				(width 0.1)
				(type default)
			)
			(layer "F.Fab")
		)
		(fp_line
			(start 0.12065 -0.2794)
			(end 0.12065 -0.3048)
			(stroke
				(width 0.1)
				(type default)
			)
			(layer "F.Fab")
		)
		(fp_line
			(start 0.67945 -0.3048)
			(end 0.67945 0.3048)
			(stroke
				(width 0.1)
				(type default)
			)
			(layer "F.Fab")
		)
		(fp_line
			(start 0.67945 0.3048)
			(end 0.120396 0.3048)
			(stroke
				(width 0.1)
				(type default)
			)
			(layer "F.Fab")
		)
		(pad "1" smd circle
			(at -0.40005 0)
			(size 0 0)
			(layers "F.Cu" "F.Mask" "F.Paste")
			(net "PCA9548_PCIE3_ADDR2")
		)
		(pad "2" smd circle
			(at 0.40005 0)
			(size 0 0)
			(layers "F.Cu" "F.Mask" "F.Paste")
			(net "GND")
		)
	)
)
